FILE_TYPE = CONNECTIVITY;
{Allegro Design Entry HDL 16.6-p007 (v16-6-112F) 10/10/2012}
"PAGE_NUMBER" = 141;
0"NC";
1"GND_NIC\g"VOLTAGE"0V";
2"GND_NIC\g"VOLTAGE"0V";
3"GND_NIC\g";
4"GND\g";
5"GND_NIC\g";
6"GND\g";
7"GND\g";
8"GND\g";
9"GND\g";
10"GND\g";
11"GND\g";
12"GND\g";
13"P3V3_STBY\g";
14"P3V3_STBY\g";
15"NIC_MDI_MNG_RX_DP";
16"NIC_MDI_MNG_RX_DN";
17"NIC_SER_P_MDI_3_DP";
18"NIC_SER_N_MDI_3_DN";
19"LED_LAN_0_N";
20"NIC_LED_ACT_ANODE_R";
21"LED_LAN_2_N";
22"NIC_MDI_MNG_TX_DP";
23"NIC_MDI_MNG_TX_DN";
24"NIC_MDI_SPRV_RJ45_0_R_DP";
25"GND_LAN_TRCT1234_C";
26"NIC_MDI_SPRV_RJ45_3_R_DN";
27"GND_LAN_TRCT1234_C";
28"NIC_MDI_SPRV_RJ45_3_R_DP";
29"LED_LAN_2_R_N";
30"LED_LAN_0_R_N";
31"NIC_MDI_SPRV_RJ45_2_R_DN";
32"NIC_SET_P_MDI_2_DP";
33"NIC_MDI_SPRV_RJ45_2_R_DP";
34"NIC_MDI_SPRV_RJ45_3_R_DP";
35"NIC_MDI_SPRV_RJ45_3_R_DN";
36"NIC_MDI_SPRV_RJ45_2_R_DP";
37"NIC_MDI_SPRV_RJ45_2_R_DN";
38"NIC_MDI_SPRV_RJ45_1_R_DP";
39"NIC_MDI_SPRV_RJ45_1_R_DN";
40"NIC_MDI_SPRV_RJ45_0_R_DN";
41"NIC_SET_N_MDI_2_DN";
42"NIC_MDI_SPRV_RJ45_0_DP";
43"NIC_MDI_SPRV_RJ45_0_DN";
44"NIC_MDI_SPRV_RJ45_1_R_DN";
45"NIC_MDI_SPRV_RJ45_0_R_DN";
46"NIC_MDI_SPRV_RJ45_0_R_DP";
47"LED_LAN_1_R_N";
48"NIC_MDI_SPRV_RJ45_1_R_DP";
49"NIC_MDI_SPRV_RJ45_1_DN";
50"NIC_MDI_SPRV_RJ45_1_DP";
51"GND_LAN_TRCT1234_C";
52"GND_LAN_TRCT1234_C";
53"LED_LAN_1_N";
54"GND_LAN_TRCT1234_C"VOLTAGE"0";
%"CAP"
"2","(-3150,4375)","0","mstr_discrete","I100";
;
BOM_COST"NT_GBE_BASE"
ROOM"NIC_SPRV"
PACK_TYPE"0402LF"
NO_XNET_CONNECTION"1"
$SEC"1"
CDS_SEC"1"
VOLTAGE"50V"
CDS_LIB"mstr_discrete"
CDS_LOCATION"C9G12"
TOLERANCE"10%"
MATERIAL"EMPTY"
VALUE"4700PF"
PART_NUMBER"A36096-066"
LOCATION"C9G12";
"A"
$PN"1"18;
"B"
$PN"2"16;
%"CAP"
"2","(-2825,4075)","0","mstr_discrete","I101";
;
ROOM"NIC_SPRV"
BOM_COST"NT_GBE_BASE"
NO_XNET_CONNECTION"1"
$SEC"1"
CDS_SEC"1"
CDS_LOCATION"C9G16"
CDS_LIB"mstr_discrete"
VOLTAGE"50V"
PACK_TYPE"0402LF"
TOLERANCE"10%"
VALUE"4700PF"
PART_NUMBER"A36096-066"
LOCATION"C9G16"
MATERIAL"EMPTY";
"A"
$PN"1"32;
"B"
$PN"2"22;
%"CAP"
"2","(-3100,4025)","0","mstr_discrete","I102";
;
BOM_COST"NT_GBE_BASE"
NO_XNET_CONNECTION"1"
$SEC"1"
CDS_SEC"1"
ROOM"NIC_SPRV"
PACK_TYPE"0402LF"
VOLTAGE"50V"
CDS_LIB"mstr_discrete"
CDS_LOCATION"C9G13"
TOLERANCE"10%"
MATERIAL"EMPTY"
VALUE"4700PF"
PART_NUMBER"A36096-066"
LOCATION"C9G13";
"A"
$PN"1"41;
"B"
$PN"2"23;
%"GND_NIC"
"1","(-4175,1700)","0","mstr_symbols","I107";
;
VOLTAGE"0.0V"
CDS_LIB"mstr_symbols"
BODY_TYPE"PLUMBING"
HDL_POWER"GND_NIC";
"A"1;
%"GND_NIC"
"1","(-3000,1700)","0","mstr_symbols","I108";
;
VOLTAGE"0.0V"
CDS_LIB"mstr_symbols"
BODY_TYPE"PLUMBING"
HDL_POWER"GND_NIC";
"A"2;
%"CONN17_H71061002"
"1","(-3575,2500)","0","mstr_conn","I109";
;
ROOM"NIC_SPRV"
CDS_LOCATION"JA9G1"
$SEC"1"
CDS_SEC"1"
BOM_COST"NT_GBE_BASE"
PACK_TYPE"PIP1"
CDS_LIB"mstr_conn"
CDS_LMAN_SYM_OUTLINE"-400,550,400,-550"
LOCATION"JA9G1"
MATERIAL"CONN"
PART_NUMBER"H71061-002";
"TRCT3"
$PN"R1"25;
"TRD4N"
$PN"R9"26;
"TRCT2"
$PN"R6"52;
"TRCT1"
$PN"R12"51;
"TRD1N"
$PN"R10"45;
"TRD2P"
$PN"R4"48;
"TRD4P"
$PN"R8"28;
"TRD3N"
$PN"R2"31;
"TRD3P"
$PN"R3"33;
"L1"
$PN"L1"30;
"TRD2N"
$PN"R5"44;
"L5"
$PN"L5"47;
"L4"
$PN"L4"20;
"MH2"
$PN"MH2"2;
"MH1"
$PN"MH1"1;
"L2"
$PN"L2"13;
"L3"
$PN"L3"29;
"TRCT4"
$PN"R7"27;
"TRD1P"
$PN"R11"46;
%"GND_NIC"
"1","(-4175,1300)","0","mstr_symbols","I110";
;
CDS_LIB"mstr_symbols"
VOLTAGE"0.0V"
BODY_TYPE"PLUMBING"
HDL_POWER"GND_NIC";
"A"3;
%"GND"
"1","(-4700,1300)","0","mstr_symbols","I111";
;
HDL_POWER"GND"
CDS_LIB"mstr_symbols"
SIZE"1B"
BODY_TYPE"PLUMBING"
VOLTAGE"0.0V";
"A\NAC"4;
%"RES"
"1","(-4450,1400)","0","mstr_discrete","I112";
;
CDS_SEC"1"
SEC_TYPE"0402"
BOM_COST"NT_GBE_BASE"
SEC"1"
ROOM"NIC_SPRV"
CDS_LIB"mstr_discrete"
CDS_LOCATION"R1U51"
MATERIAL"CHIP"
PART_NUMBER"G21497-005"
TOLERANCE"5%"
LOCATION"R1U51"
VALUE"0.0"
PACK_TYPE"0402"
WATTAGE"1/16W";
"B"
$PN"2"3;
"A"
$PN"1"4;
%"GND_NIC"
"1","(-4175,925)","0","mstr_symbols","I113";
;
BODY_TYPE"PLUMBING"
CDS_LIB"mstr_symbols"
VOLTAGE"0.0V"
HDL_POWER"GND_NIC";
"A"5;
%"RES"
"1","(-4450,1000)","0","mstr_discrete","I114";
;
CDS_SEC"1"
BOM_COST"NT_GBE_BASE"
SEC_TYPE"0402"
SEC"1"
CDS_LOCATION"R1U3"
ROOM"NIC_SPRV"
CDS_LIB"mstr_discrete"
PART_NUMBER"G21497-005"
LOCATION"R1U3"
MATERIAL"CHIP"
PACK_TYPE"0402"
TOLERANCE"5%"
VALUE"0.0"
WATTAGE"1/16W";
"B"
$PN"2"5;
"A"
$PN"1"6;
%"GND"
"1","(-4700,900)","0","mstr_symbols","I115";
;
HDL_POWER"GND"
VOLTAGE"0.0V"
BODY_TYPE"PLUMBING"
SIZE"1B"
CDS_LIB"mstr_symbols";
"A\NAC"6;
%"RES"
"1","(-2375,2400)","0","mstr_discrete","I28";
;
CDS_SEC"1"
SEC_TYPE"0402"
SEC"1"
BOM_COST"NT_GBE_BASE"
ROOM"NIC_SPRV"
CDS_LIB"mstr_discrete"
CDS_LOCATION"R9G3"
VALUE"150.0"
PART_NUMBER"G21796-009"
PACK_TYPE"0402"
WATTAGE"1/16W"
TOLERANCE"1%"
LOCATION"R9G3"
MATERIAL"CHIP";
"B"
$PN"2"19;
"A"
$PN"1"30;
%"RES"
"1","(-2550,2300)","0","mstr_discrete","I30";
;
CDS_SEC"1"
CDS_LIB"mstr_discrete"
BOM_COST"NT_GBE_BASE"
SEC_TYPE"0402"
SEC"1"
CDS_LOCATION"R9G2"
ROOM"NIC_SPRV"
MATERIAL"CHIP"
VALUE"150.0"
TOLERANCE"1%"
PACK_TYPE"0402"
LOCATION"R9G2"
PART_NUMBER"G21796-009"
WATTAGE"1/16W";
"B"
$PN"2"21;
"A"
$PN"1"29;
%"CAP_A"
"1","(-5575,2150)","0","dev_discrete","I33";
;
SEC"1"
SEC_TYPE"0402V"
BOM_COST"NT_GBE_BASE"
CDS_SEC"1"
ROOM"NIC_SPRV"
CDS_LOCATION"C9G7"
CDS_LIB"dev_discrete"
VALUE"0.1UF"
MATERIAL"X7R"
VOLTAGE"16V"
TOLERANCE"10%"
LOCATION"C9G7"
PART_NUMBER"A36096-030"
PACK_TYPE"0402V";
"B"
$PN"2"7;
"A"
$PN"1"13;
%"GND"
"1","(-5575,1700)","0","mstr_symbols","I35";
;
VOLTAGE"0.0V"
SIZE"1B"
CDS_LIB"mstr_symbols"
BODY_TYPE"PLUMBING"
HDL_POWER"GND";
"A\NAC"7;
%"CAP"
"1","(-1700,925)","0","mstr_discrete","I36";
;
CDS_SEC"1"
ROOM"NIC_SPRV"
SEC_TYPE"0402LF"
BOM_COST"NT_GBE_BASE"
SEC"1"
CDS_LOCATION"C9G2"
CDS_LIB"mstr_discrete"
LOCATION"C9G2"
PACK_TYPE"0402LF"
VALUE"470PF"
PART_NUMBER"A36096-049"
MATERIAL"X7R"
VOLTAGE"50V"
TOLERANCE"10%";
"A"
$PN"1"14;
"B"
$PN"2"8;
%"GND"
"1","(-1700,700)","0","mstr_symbols","I38";
;
HDL_POWER"GND"
BODY_TYPE"PLUMBING"
CDS_LIB"mstr_symbols"
SIZE"1B"
VOLTAGE"0.0V";
"A\NAC"8;
%"CAP_A"
"1","(-5925,1250)","0","dev_discrete","I46";
;
SEC"1"
SEC_TYPE"0402V"
CDS_SEC"1"
BOM_COST"NT_GBE_BASE"
CDS_LOCATION"C9G4"
ROOM"NIC_SPRV"
CDS_LIB"dev_discrete"
PART_NUMBER"A36096-030"
PACK_TYPE"0402V"
TOLERANCE"10%"
VALUE"0.1UF"
LOCATION"C9G4"
MATERIAL"X7R"
VOLTAGE"16V";
"B"
$PN"2"9;
"A"
$PN"1"54;
%"CAP_A"
"1","(-6250,1250)","0","dev_discrete","I47";
;
SEC"1"
SEC_TYPE"0402V"
BOM_COST"NT_GBE_BASE"
ROOM"NIC_SPRV"
CDS_SEC"1"
CDS_LOCATION"C9G6"
CDS_LIB"dev_discrete"
MATERIAL"X7R"
VOLTAGE"16V"
PACK_TYPE"0402V"
TOLERANCE"10%"
VALUE"0.1UF"
PART_NUMBER"A36096-030"
LOCATION"C9G6";
"B"
$PN"2"9;
"A"
$PN"1"54;
%"CAP"
"1","(-6600,1250)","0","mstr_discrete","I48";
;
CDS_SEC"1"
ROOM"NIC_SPRV"
CDS_LOCATION"C9G5"
SEC"1"
SEC_TYPE"0402"
BOM_COST"NT_GBE_BASE"
CDS_LIB"mstr_discrete"
PART_NUMBER"G71842-007"
LOCATION"C9G5"
VALUE"1.0UF"
MATERIAL"X7S"
VOLTAGE"16V"
PACK_TYPE"0402"
TOLERANCE"10%";
"A"
$PN"1"54;
"B"
$PN"2"9;
%"GND"
"1","(-6600,950)","0","mstr_symbols","I50";
;
HDL_POWER"GND"
BODY_TYPE"PLUMBING"
SIZE"1B"
CDS_LIB"mstr_symbols"
VOLTAGE"0.0V";
"A\NAC"9;
%"RES"
"1","(-4550,2150)","0","mstr_discrete","I54";
;
CDS_SEC"1"
SEC_TYPE"0402"
SEC"1"
BOM_COST"NT_GBE_BASE"
CDS_LIB"mstr_discrete"
CDS_LOCATION"R9G1"
ROOM"NIC_SPRV"
VALUE"150.0"
PART_NUMBER"G21796-009"
TOLERANCE"1%"
PACK_TYPE"0402"
LOCATION"R9G1"
WATTAGE"1/16W"
MATERIAL"CHIP";
"B"
$PN"2"47;
"A"
$PN"1"53;
%"RES"
"1","(-1925,1175)","0","mstr_discrete","I56";
;
CDS_SEC"1"
BOM_COST"NT_GBE_BASE"
SEC_TYPE"0402"
ROOM"NIC_SPRV"
SEC"1"
CDS_LOCATION"R9G4"
CDS_LIB"mstr_discrete"
PACK_TYPE"0402"
PART_NUMBER"G21497-005"
LOCATION"R9G4"
MATERIAL"CHIP"
TOLERANCE"5%"
VALUE"0.0"
WATTAGE"1/16W";
"B"
$PN"2"14;
"A"
$PN"1"20;
%"CAP"
"1","(-2050,2050)","0","mstr_discrete","I58";
;
CDS_SEC"1"
SEC_TYPE"0402LF"
BOM_COST"NT_GBE_BASE"
SEC"1"
CDS_LOCATION"C9G1"
ROOM"NIC_SPRV"
CDS_LIB"mstr_discrete"
LOCATION"C9G1"
VALUE"470PF"
VOLTAGE"50V"
PART_NUMBER"A36096-049"
MATERIAL"X7R"
PACK_TYPE"0402LF"
TOLERANCE"10%";
"A"
$PN"1"21;
"B"
$PN"2"11;
%"CAP"
"1","(-1750,2050)","0","mstr_discrete","I59";
;
CDS_SEC"1"
ROOM"NIC_SPRV"
CDS_LIB"mstr_discrete"
BOM_COST"NT_GBE_BASE"
SEC"1"
CDS_LOCATION"C9G3"
SEC_TYPE"0402LF"
VOLTAGE"50V"
VALUE"470PF"
LOCATION"C9G3"
PACK_TYPE"0402LF"
PART_NUMBER"A36096-049"
TOLERANCE"10%"
MATERIAL"X7R";
"A"
$PN"1"19;
"B"
$PN"2"12;
%"CAP"
"1","(-4800,1950)","0","mstr_discrete","I60";
;
CDS_SEC"1"
BOM_COST"NT_GBE_BASE"
SEC_TYPE"0402LF"
SEC"1"
CDS_LOCATION"C9F22"
ROOM"NIC_SPRV"
CDS_LIB"mstr_discrete"
LOCATION"C9F22"
PACK_TYPE"0402LF"
VALUE"470PF"
PART_NUMBER"A36096-049"
MATERIAL"X7R"
VOLTAGE"50V"
TOLERANCE"10%";
"A"
$PN"1"53;
"B"
$PN"2"10;
%"GND"
"1","(-4800,1725)","0","mstr_symbols","I61";
;
HDL_POWER"GND"
BODY_TYPE"PLUMBING"
CDS_LIB"mstr_symbols"
SIZE"1B"
VOLTAGE"0.0V";
"A\NAC"10;
%"GND"
"1","(-2050,1700)","0","mstr_symbols","I62";
;
SIZE"1B"
HDL_POWER"GND"
VOLTAGE"0.0V"
CDS_LIB"mstr_symbols"
BODY_TYPE"PLUMBING";
"A\NAC"11;
%"GND"
"1","(-1750,1700)","0","mstr_symbols","I63";
;
HDL_POWER"GND"
SIZE"1B"
CDS_LIB"mstr_symbols"
VOLTAGE"0.0V"
BODY_TYPE"PLUMBING";
"A\NAC"12;
%"P3V3_STBY"
"1","(-5575,2675)","0","mstr_symbols","I64";
;
BODY_TYPE"PLUMBING"
CDS_LIB"mstr_symbols"
SIZE"1B"
VOLTAGE"3.3V"
HDL_POWER"P3V3_STBY";
"G\NAC"13;
%"P3V3_STBY"
"1","(-1700,1425)","0","mstr_symbols","I65";
;
VOLTAGE"3.3V"
SIZE"1B"
CDS_LIB"mstr_symbols"
BODY_TYPE"PLUMBING"
HDL_POWER"P3V3_STBY";
"G\NAC"14;
%"RES"
"1","(-3550,3775)","0","mstr_discrete","I75";
;
BOM_COST"NT_GBE_BASE"
ROOM"NIC_SPRV"
PACK_TYPE"0402"
CDS_LIB"mstr_discrete"
MATERIAL"CHIP"
$SEC"1"
CDS_SEC"1"
WATTAGE"1/16W"
CDS_LOCATION"R9G9"
VALUE"0.0"
PART_NUMBER"G21497-005"
LOCATION"R9G9"
TOLERANCE"5%";
"B"
$PN"2"34;
"A"
$PN"1"17;
%"RES"
"1","(-3550,3725)","0","mstr_discrete","I76";
;
BOM_COST"NT_GBE_BASE"
ROOM"NIC_SPRV"
PACK_TYPE"0402"
CDS_LIB"mstr_discrete"
MATERIAL"CHIP"
$SEC"1"
CDS_SEC"1"
CDS_LOCATION"R9G11"
WATTAGE"1/16W"
VALUE"0.0"
PART_NUMBER"G21497-005"
LOCATION"R9G11"
TOLERANCE"5%";
"B"
$PN"2"35;
"A"
$PN"1"18;
%"RES"
"1","(-3550,3675)","0","mstr_discrete","I77";
;
ROOM"NIC_SPRV"
BOM_COST"NT_GBE_BASE"
PACK_TYPE"0402"
CDS_LIB"mstr_discrete"
MATERIAL"CHIP"
$SEC"1"
CDS_SEC"1"
WATTAGE"1/16W"
CDS_LOCATION"R9G18"
VALUE"0.0"
PART_NUMBER"G21497-005"
LOCATION"R9G18"
TOLERANCE"5%";
"B"
$PN"2"36;
"A"
$PN"1"32;
%"RES"
"1","(-3550,3625)","0","mstr_discrete","I78";
;
ROOM"NIC_SPRV"
BOM_COST"NT_GBE_BASE"
CDS_LIB"mstr_discrete"
MATERIAL"CHIP"
PACK_TYPE"0402"
$SEC"1"
CDS_SEC"1"
CDS_LOCATION"R9G17"
WATTAGE"1/16W"
VALUE"0.0"
PART_NUMBER"G21497-005"
LOCATION"R9G17"
TOLERANCE"5%";
"B"
$PN"2"37;
"A"
$PN"1"41;
%"RES"
"1","(-3550,3575)","0","mstr_discrete","I79";
;
ROOM"NIC_SPRV"
BOM_COST"NT_GBE_BASE"
CDS_LIB"mstr_discrete"
PACK_TYPE"0402"
MATERIAL"CHIP"
CDS_SEC"1"
$SEC"1"
CDS_LOCATION"R9G19"
WATTAGE"1/16W"
VALUE"0.0"
PART_NUMBER"G21497-005"
LOCATION"R9G19"
TOLERANCE"5%";
"B"
$PN"2"38;
"A"
$PN"1"50;
%"RES"
"1","(-3550,3525)","0","mstr_discrete","I80";
;
BOM_COST"NT_GBE_BASE"
ROOM"NIC_SPRV"
PACK_TYPE"0402"
MATERIAL"CHIP"
CDS_LIB"mstr_discrete"
CDS_SEC"1"
$SEC"1"
WATTAGE"1/16W"
CDS_LOCATION"R9G20"
VALUE"0.0"
PART_NUMBER"G21497-005"
LOCATION"R9G20"
TOLERANCE"5%";
"B"
$PN"2"39;
"A"
$PN"1"49;
%"RES"
"1","(-3550,3475)","0","mstr_discrete","I81";
;
BOM_COST"NT_GBE_BASE"
ROOM"NIC_SPRV"
PACK_TYPE"0402"
CDS_LIB"mstr_discrete"
MATERIAL"CHIP"
CDS_SEC"1"
$SEC"1"
CDS_LOCATION"R9G24"
WATTAGE"1/16W"
VALUE"0.0"
PART_NUMBER"G21497-005"
LOCATION"R9G24"
TOLERANCE"5%";
"B"
$PN"2"24;
"A"
$PN"1"42;
%"RES"
"1","(-3550,3425)","0","mstr_discrete","I82";
;
ROOM"NIC_SPRV"
BOM_COST"NT_GBE_BASE"
PACK_TYPE"0402"
CDS_LIB"mstr_discrete"
MATERIAL"CHIP"
$SEC"1"
CDS_SEC"1"
WATTAGE"1/16W"
CDS_LOCATION"R9G22"
VALUE"0.0"
PART_NUMBER"G21497-005"
LOCATION"R9G22"
TOLERANCE"5%";
"B"
$PN"2"40;
"A"
$PN"1"43;
%"CAP"
"2","(-2875,4425)","0","mstr_discrete","I99";
;
NO_XNET_CONNECTION"1"
$SEC"1"
CDS_SEC"1"
ROOM"NIC_SPRV"
BOM_COST"NT_GBE_BASE"
PACK_TYPE"0402LF"
VOLTAGE"50V"
CDS_LIB"mstr_discrete"
CDS_LOCATION"C9G9"
MATERIAL"EMPTY"
TOLERANCE"10%"
VALUE"4700PF"
PART_NUMBER"A36096-066"
LOCATION"C9G9";
"A"
$PN"1"17;
"B"
$PN"2"15;
END.
